# TIMECARD (Time Appliance Project (Time Card)) — schematic netlist excerpt (pin names and nets, part order shuffled) for the footprints in the layout excerpt that follows; sources: Cadence DE-HDL packaged netlist, KiCad conversion of R4006-B0001-02_R01.brd

R408  RESISTOR  4.7KOHM 1%  pkg SMC_0402R_H016  page 17 : \1\ = XP3R3V_FPGA ; \2\ = UNNAMED_6_LM75BDPTSSOP8_I59_A2
TP141  TP_PIONT  pkg TP010CT020B030_PTH  page 25 : \1\ = IO_L24N_34
TP135  TP_PIONT  pkg TP010CT020B030_PTH  page 25 : \1\ = IO_L21N_34

(kicad_pcb
	(version 20260206)
	(generator "pcbnew")
	(generator_version "10.0")
	(general
		(thickness 1.6)
		(legacy_teardrops no)
	)
	(paper "A4")
	(title_block
		(title "timecard-production-celestica-r4006 — R4006-B0001-02_R01.brd")
		(comment 1 "Time Appliance Project (Time Card) / footprints 561-563 of 1113")
	)
	(layers
		(0 "F.Cu" signal "TOP")
		(4 "In1.Cu" signal "L02_GND1")
		(6 "In2.Cu" signal "L03_SIG1")
		(8 "In3.Cu" signal "L04_GND2")
		(10 "In4.Cu" signal "L05_VCC1")
		(12 "In5.Cu" signal "L06_VCC2")
		(14 "In6.Cu" signal "L07_GND3")
		(16 "In7.Cu" signal "L08_SIG2")
		(18 "In8.Cu" signal "L09_GND4")
		(2 "B.Cu" signal "BOTTOM")
		(9 "F.Adhes" user "F.Adhesive")
		(11 "B.Adhes" user "B.Adhesive")
		(13 "F.Paste" user "Package Geometry/Pastemask Top")
		(15 "B.Paste" user "Package Geometry/Pastemask Bottom")
		(5 "F.SilkS" user "Ref Des/Silkscreen Top")
		(7 "B.SilkS" user "Ref Des/Silkscreen Bottom")
		(1 "F.Mask" user "Board Geometry/Soldermask Top")
		(3 "B.Mask" user "Board Geometry/Soldermask Bottom")
		(17 "Dwgs.User" user "User.Drawings")
		(19 "Cmts.User" user "User.Comments")
		(21 "Eco1.User" user "User.Eco1")
		(23 "Eco2.User" user "User.Eco2")
		(25 "Edge.Cuts" user "Board Geometry/Outline")
		(27 "Margin" user)
		(31 "F.CrtYd" user "Package Geometry/Place Bound Top")
		(29 "B.CrtYd" user "Package Geometry/Place Bound Bottom")
		(35 "F.Fab" user "Ref Des/Assembly Top")
		(33 "B.Fab" user "Ref Des/Assembly Bottom")
	)
	(footprint ""
		(layer "F.Cu")
		(at 118.346982 -41.32326)
		(property "Reference" "TP141"
			(at 0 0 0)
			(layer "F.SilkS")
			(hide yes)
			(effects
				(font
					(size 1.27 1.27)
				)
			)
		)
		(property "Value" ""
			(at 0 0 0)
			(layer "F.Fab")
			(effects
				(font
					(size 1.27 1.27)
				)
			)
		)
		(property "Device Type" "TP_PIONT-TP010CT020B030_PTH-TPA"
			(at -1.341882 0.996696 0)
			(unlocked yes)
			(layer "F.Fab")
			(hide yes)
			(effects
				(font
					(size 0.7874 0.5842)
					(thickness 0.1524)
				)
				(justify left)
			)
		)
		(duplicate_pad_numbers_are_jumpers no)
		(fp_poly
			(pts
				(arc
					(start 0.889 0)
					(mid -0.889 0)
					(end 0.889 0)
				)
			)
			(stroke
				(width 0)
				(type default)
			)
			(fill no)
			(layer "B.CrtYd")
		)
		(fp_poly
			(pts
				(arc
					(start 0.889 0)
					(mid -0.889 0)
					(end 0.889 0)
				)
			)
			(stroke
				(width 0)
				(type default)
			)
			(fill no)
			(layer "F.CrtYd")
		)
		(pad "1" thru_hole circle
			(at 0 0)
			(size 0.508 0.508)
			(drill 0.254)
			(layers "*.Cu" "*.Mask")
			(remove_unused_layers no)
			(net "IO_L24N_34")
			(clearance 0.1016)
			(padstack
				(mode front_inner_back)
				(layer "Inner"
					(shape circle)
					(size 0.508 0.508)
					(clearance 0.1016)
				)
				(layer "B.Cu"
					(shape circle)
					(size 0.762 0.762)
					(clearance -0.0254)
				)
			)
		)
	)
	(footprint ""
		(layer "F.Cu")
		(at 52.9082 -74.9808 90)
		(property "Reference" "R408"
			(at -0.5588 4.53517 90)
			(unlocked yes)
			(layer "F.SilkS")
			(effects
				(font
					(size 0.7874 0.5842)
					(thickness 0.1524)
				)
			)
		)
		(property "Value" "VAL*"
			(at 0.02032 2.13233 90)
			(unlocked yes)
			(layer "F.Fab")
			(hide yes)
			(effects
				(font
					(size 0.7874 0.5842)
					(thickness 0.1524)
				)
			)
		)
		(property "Device Type" "RESISTOR-G155-14701-01,4.7KOHMA"
			(at 0.008382 1.210564 90)
			(unlocked yes)
			(layer "F.Fab")
			(hide yes)
			(effects
				(font
					(size 0.7874 0.5842)
					(thickness 0.1524)
				)
			)
		)
		(property "User Part Number" "PARTNUM*"
			(at 0.02032 4.024884 90)
			(unlocked yes)
			(layer "Cmts.User")
			(hide yes)
			(effects
				(font
					(size 0.7874 0.5842)
					(thickness 0.1524)
				)
			)
		)
		(property "Tolerance" "TOL*"
			(at 0.044704 3.05435 90)
			(unlocked yes)
			(layer "Cmts.User")
			(hide yes)
			(effects
				(font
					(size 0.7874 0.5842)
					(thickness 0.1524)
				)
			)
		)
		(duplicate_pad_numbers_are_jumpers no)
		(fp_line
			(start 1.143 -0.5588)
			(end -1.143 -0.5588)
			(stroke
				(width 0.1)
				(type default)
			)
			(layer "F.SilkS")
		)
		(fp_line
			(start -1.143 -0.5588)
			(end -1.143 0.5588)
			(stroke
				(width 0.1)
				(type default)
			)
			(layer "F.SilkS")
		)
		(fp_line
			(start 1.143 0.5588)
			(end 1.143 -0.5588)
			(stroke
				(width 0.1)
				(type default)
			)
			(layer "F.SilkS")
		)
		(fp_line
			(start -1.143 0.5588)
			(end 1.143 0.5588)
			(stroke
				(width 0.1)
				(type default)
			)
			(layer "F.SilkS")
		)
		(fp_rect
			(start -1.143 0.5588)
			(end 1.143 -0.5588)
			(stroke
				(width 0)
				(type default)
			)
			(fill no)
			(layer "F.CrtYd")
		)
		(fp_line
			(start 0.508 -0.3048)
			(end -0.508 -0.3048)
			(stroke
				(width 0.1)
				(type default)
			)
			(layer "F.Fab")
		)
		(fp_line
			(start -0.508 -0.3048)
			(end -0.508 0.3048)
			(stroke
				(width 0.1)
				(type default)
			)
			(layer "F.Fab")
		)
		(fp_line
			(start 0.508 0.3048)
			(end 0.508 -0.3048)
			(stroke
				(width 0.1)
				(type default)
			)
			(layer "F.Fab")
		)
		(fp_line
			(start -0.508 0.3048)
			(end 0.508 0.3048)
			(stroke
				(width 0.1)
				(type default)
			)
			(layer "F.Fab")
		)
		(pad "1" smd rect
			(at -0.5334 0 90)
			(size 0.7112 0.6096)
			(layers "F.Cu" "F.Mask" "F.Paste")
			(net "XP3R3V_FPGA")
		)
		(pad "2" smd rect
			(at 0.5334 0 90)
			(size 0.7112 0.6096)
			(layers "F.Cu" "F.Mask" "F.Paste")
			(net "UNNAMED_6_LM75BDPTSSOP8_I59_A2")
		)
		(zone
			(layer "F.Cu")
			(hatch none 0.5)
			(connect_pads
				(clearance 0)
			)
			(min_thickness 0.25)
			(keepout
				(tracks allowed)
				(vias not_allowed)
				(pads allowed)
				(copperpour not_allowed)
				(footprints allowed)
			)
			(placement
				(enabled no)
				(sheetname "")
			)
			(fill
				(thermal_gap 0.5)
				(thermal_bridge_width 0.5)
				(island_removal_mode 0)
			)
			(polygon
				(pts
					(xy 53.213 -74.9046) (xy 53.213 -75.057) (xy 52.6034 -75.057) (xy 52.6034 -74.9046)
				)
			)
		)
		(zone
			(layer "F.Cu")
			(hatch none 0.5)
			(connect_pads
				(clearance 0)
			)
			(min_thickness 0.25)
			(keepout
				(tracks not_allowed)
				(vias allowed)
				(pads allowed)
				(copperpour not_allowed)
				(footprints allowed)
			)
			(placement
				(enabled no)
				(sheetname "")
			)
			(fill
				(thermal_gap 0.5)
				(thermal_bridge_width 0.5)
				(island_removal_mode 0)
			)
			(polygon
				(pts
					(xy 53.213 -74.9046) (xy 53.213 -75.057) (xy 52.6034 -75.057) (xy 52.6034 -74.9046)
				)
			)
		)
	)
	(footprint ""
		(layer "F.Cu")
		(at 126.365 -37.719)
		(property "Reference" "TP135"
			(at 2.95275 2.2098 90)
			(unlocked yes)
			(layer "F.SilkS")
			(effects
				(font
					(size 0.635 0.4064)
					(thickness 0.1524)
				)
				(justify left)
			)
		)
		(property "Value" ""
			(at 0 0 0)
			(layer "F.Fab")
			(effects
				(font
					(size 1.27 1.27)
				)
			)
		)
		(property "Device Type" "TP_PIONT-TP010CT020B030_PTH-TPA"
			(at -1.341882 0.996696 0)
			(unlocked yes)
			(layer "F.Fab")
			(hide yes)
			(effects
				(font
					(size 0.7874 0.5842)
					(thickness 0.1524)
				)
				(justify left)
			)
		)
		(duplicate_pad_numbers_are_jumpers no)
		(fp_poly
			(pts
				(arc
					(start 0.889 0)
					(mid -0.889 0)
					(end 0.889 0)
				)
			)
			(stroke
				(width 0)
				(type default)
			)
			(fill no)
			(layer "B.CrtYd")
		)
		(fp_poly
			(pts
				(arc
					(start 0.889 0)
					(mid -0.889 0)
					(end 0.889 0)
				)
			)
			(stroke
				(width 0)
				(type default)
			)
			(fill no)
			(layer "F.CrtYd")
		)
		(pad "1" thru_hole circle
			(at 0 0)
			(size 0.508 0.508)
			(drill 0.254)
			(layers "*.Cu" "*.Mask")
			(remove_unused_layers no)
			(net "IO_L21N_34")
			(clearance 0.1016)
			(padstack
				(mode front_inner_back)
				(layer "Inner"
					(shape circle)
					(size 0.508 0.508)
					(clearance 0.1016)
				)
				(layer "B.Cu"
					(shape circle)
					(size 0.762 0.762)
					(clearance -0.0254)
				)
			)
		)
	)
)
